#ISCELL
  pure_quanta quanta_title_block_c *
  *
#ISCELL
  standard offpage *
  page121_i1
#CELL
  pure_quanta q_res *
  page121_i10
#ISCELL
  standard offpage *
  page121_i11
#ISCELL
  logical_power universal_power *
  page121_i12
#CELL
  pure_quanta q_res *
  page121_i13
#ISCELL
  logical_power universal_power *
  page121_i14
#CELL
  pure_quanta q_res *
  page121_i15
#CELL
  pure_quanta q_res *
  page121_i16
#CELL
  pure_quanta bc847bpn *
  page121_i17
#ISCELL
  logical_power universal_power *
  page121_i18
#CELL
  pure_quanta q_res *
  page121_i19
#ISCELL
  standard offpage *
  page121_i2
#ISCELL
  logical_power universal_power *
  page121_i20
#CELL
  pure_quanta bc847bpn *
  page121_i21
#ISCELL
  logical_power universal_gnd *
  page121_i22
#CELL
  pure_quanta q_res *
  page121_i23
#ISCELL
  logical_power universal_power *
  page121_i24
#ISCELL
  logical_power universal_power *
  page121_i25
#CELL
  pure_quanta q_res *
  page121_i26
#ISCELL
  standard offpage *
  page121_i27
#ISCELL
  standard offpage *
  page121_i28
#CELL
  pure_quanta q_res *
  page121_i29
#ISCELL
  standard offpage *
  page121_i3
#ISCELL
  standard offpage *
  page121_i30
#CELL
  pure_quanta bc847bpn *
  page121_i31
#ISCELL
  logical_power universal_gnd *
  page121_i32
#CELL
  pure_quanta q_res *
  page121_i33
#ISCELL
  logical_power universal_power *
  page121_i34
#CELL
  pure_quanta q_res *
  page121_i35
#ISCELL
  standard offpage *
  page121_i36
#CELL
  pure_quanta q_res *
  page121_i4
#CELL
  pure_quanta q_res *
  page121_i5
#CELL
  pure_quanta q_res *
  page121_i6
#CELL
  pure_quanta q_res *
  page121_i7
#CELL
  pure_quanta bc847bpn *
  page121_i8
#ISCELL
  logical_power universal_power *
  page121_i9
